(kicad_pcb
	(version 20260206)
	(generator "pcbnew")
	(generator_version "10.0")
	(general
		(thickness 1.21888)
		(legacy_teardrops no)
	)
	(paper "A4")
	(title_block
		(title "timecard-v7 — TimeCard-DC-V7_EXP.PcbDoc")
		(comment 1 "Time Appliance Project (Time Card) / footprints 1-8 of 160")
	)
	(layers
		(0 "F.Cu" signal "TOP")
		(4 "In1.Cu" signal "SGND")
		(6 "In2.Cu" signal "IN1")
		(8 "In3.Cu" signal "IN2")
		(10 "In4.Cu" signal "SGND1")
		(2 "B.Cu" signal "BOTTOM")
		(9 "F.Adhes" user "F.Adhesive")
		(11 "B.Adhes" user "B.Adhesive")
		(13 "F.Paste" user "Top Paste")
		(15 "B.Paste" user "Bottom Paste")
		(5 "F.SilkS" user "Top Overlay")
		(7 "B.SilkS" user "Bottom Overlay")
		(1 "F.Mask" user "Top Solder")
		(3 "B.Mask" user "Bottom Solder")
		(17 "Dwgs.User" user "User.Drawings")
		(19 "Cmts.User" user "User.Comments")
		(21 "Eco1.User" user "User.Eco1")
		(23 "Eco2.User" user "User.Eco2")
		(25 "Edge.Cuts" user)
		(27 "Margin" user)
		(31 "F.CrtYd" user "Top Courtyard")
		(29 "B.CrtYd" user "Bottom Courtyard")
		(35 "F.Fab" user "Top Component Center")
		(33 "B.Fab" user "Bottom Component Center")
	)
	(footprint "Vault:RESC1608X55X30NL15T15"
		(layer "F.Cu")
		(at 82.3761 112.1162 -90)
		(property "Reference" "R30"
			(at 4 -0.593345 90)
			(unlocked yes)
			(layer "F.SilkS")
			(effects
				(font
					(size 0.762 0.762)
					(thickness 0.2286)
				)
				(justify left bottom)
			)
		)
		(property "Value" "4.7K"
			(at 3.72999 0.4445 0)
			(unlocked yes)
			(layer "F.SilkS")
			(hide yes)
			(effects
				(font
					(size 1.524 1.524)
					(thickness 0.254)
				)
				(justify left bottom)
			)
		)
		(sheetname "USER_IO")
		(sheetfile "USER_IO.kicad_sch")
		(duplicate_pad_numbers_are_jumpers no)
		(pad "1" smd rect
			(at -0.75 0)
			(size 0.95 0.95)
			(layers "F.Cu" "F.Mask" "F.Paste")
			(net "ANT2_IO_IN")
		)
		(pad "2" smd rect
			(at 0.75 0)
			(size 0.95 0.95)
			(layers "F.Cu" "F.Mask" "F.Paste")
			(net "+3.3V")
		)
	)
	(footprint "SA53:SA53"
		(locked yes)
		(layer "F.Cu")
		(at 120.49358 116.5662 180)
		(property "Reference" "U10"
			(at -22.46112 27.623069 0)
			(unlocked yes)
			(layer "F.SilkS")
			(effects
				(font
					(size 0.762 0.762)
					(thickness 0.2286)
				)
			)
		)
		(property "Value" "MAC-SA5X"
			(at -18.30259 28.464002 180)
			(unlocked yes)
			(layer "F.SilkS")
			(hide yes)
			(effects
				(font
					(size 1.524 1.524)
					(thickness 0.254)
				)
			)
		)
		(sheetname "MAC")
		(sheetfile "MAC.kicad_sch")
		(duplicate_pad_numbers_are_jumpers no)
		(fp_line
			(start 26.26748 26.75)
			(end -24.53252 26.75)
			(stroke
				(width 0.254)
				(type solid)
			)
			(layer "F.SilkS")
		)
		(fp_line
			(start 26.26748 -24.05)
			(end 26.26748 26.75)
			(stroke
				(width 0.254)
				(type solid)
			)
			(layer "F.SilkS")
		)
		(fp_line
			(start 26.26748 -24.05)
			(end -24.53252 -24.05)
			(stroke
				(width 0.254)
				(type solid)
			)
			(layer "F.SilkS")
		)
		(fp_line
			(start -24.53252 -24.05)
			(end -24.53252 26.75)
			(stroke
				(width 0.254)
				(type solid)
			)
			(layer "F.SilkS")
		)
		(fp_circle
			(center -15.74749 3.64128)
			(end -15.74749 3.76828)
			(stroke
				(width 0.254)
				(type solid)
			)
			(fill no)
			(layer "F.SilkS")
		)
		(pad "1" smd rect
			(at -17.16749 3.64128 270)
			(size 0.25 1.8)
			(layers "F.Cu" "F.Mask" "F.Paste")
			(net "MAC_PPS_IN1+")
		)
		(pad "2" smd rect
			(at -21.16749 3.64128 270)
			(size 0.25 1.8)
			(layers "F.Cu" "F.Mask" "F.Paste")
			(net "MAC_USB+")
		)
		(pad "3" smd rect
			(at -17.16749 3.13328 270)
			(size 0.25 1.8)
			(layers "F.Cu" "F.Mask" "F.Paste")
			(net "MAC_PPS_IN1-")
		)
		(pad "4" smd rect
			(at -21.16749 3.13328 270)
			(size 0.25 1.8)
			(layers "F.Cu" "F.Mask" "F.Paste")
			(net "MAC_USB-")
		)
		(pad "5" smd rect
			(at -17.16749 2.62528 270)
			(size 0.25 1.8)
			(layers "F.Cu" "F.Mask" "F.Paste")
			(net "MAC_PPS_IN0+")
		)
		(pad "6" smd rect
			(at -21.16749 2.62528 270)
			(size 0.25 1.8)
			(layers "F.Cu" "F.Mask" "F.Paste")
			(net "MAC_USB_PWR")
		)
		(pad "7" smd rect
			(at -17.16749 2.11728 270)
			(size 0.25 1.8)
			(layers "F.Cu" "F.Mask" "F.Paste")
			(net "MAC_PPS_IN0-")
		)
		(pad "8" smd rect
			(at -21.16749 2.11728 270)
			(size 0.25 1.8)
			(layers "F.Cu" "F.Mask" "F.Paste")
			(net "GND")
		)
		(pad "9" smd rect
			(at -17.16749 1.60928 270)
			(size 0.25 1.8)
			(layers "F.Cu" "F.Mask" "F.Paste")
			(net "GND")
		)
		(pad "10" smd rect
			(at -21.16749 1.60928 270)
			(size 0.25 1.8)
			(layers "F.Cu" "F.Mask" "F.Paste")
		)
		(pad "11" smd rect
			(at -17.16749 1.10128 270)
			(size 0.25 1.8)
			(layers "F.Cu" "F.Mask" "F.Paste")
		)
		(pad "12" smd rect
			(at -21.16749 1.10128 270)
			(size 0.25 1.8)
			(layers "F.Cu" "F.Mask" "F.Paste")
		)
		(pad "13" smd rect
			(at -17.16749 0.59328 270)
			(size 0.25 1.8)
			(layers "F.Cu" "F.Mask" "F.Paste")
		)
		(pad "14" smd rect
			(at -21.16749 0.59328 270)
			(size 0.25 1.8)
			(layers "F.Cu" "F.Mask" "F.Paste")
		)
		(pad "15" smd rect
			(at -17.16749 0.08528 270)
			(size 0.25 1.8)
			(layers "F.Cu" "F.Mask" "F.Paste")
			(net "GND")
		)
		(pad "16" smd rect
			(at -21.16749 0.08528 270)
			(size 0.25 1.8)
			(layers "F.Cu" "F.Mask" "F.Paste")
		)
		(pad "17" smd rect
			(at -17.16749 -0.42272 270)
			(size 0.25 1.8)
			(layers "F.Cu" "F.Mask" "F.Paste")
			(net "MAC_PPS_OUT+")
		)
		(pad "18" smd rect
			(at -21.16749 -0.42272 270)
			(size 0.25 1.8)
			(layers "F.Cu" "F.Mask" "F.Paste")
		)
		(pad "19" smd rect
			(at -17.16749 -0.93072 270)
			(size 0.25 1.8)
			(layers "F.Cu" "F.Mask" "F.Paste")
			(net "MAC_PPS_OUT-")
		)
		(pad "20" smd rect
			(at -21.16749 -0.93072 270)
			(size 0.25 1.8)
			(layers "F.Cu" "F.Mask" "F.Paste")
			(net "MAC_ALARM")
		)
		(pad "P1" thru_hole circle
			(at 21.16748 21.65 90)
			(size 1.905 1.905)
			(drill 1.27)
			(layers "*.Cu" "*.Mask")
			(remove_unused_layers no)
			(net "MAC_FREQ_CTRL")
			(thermal_bridge_angle 90)
		)
		(pad "P2" thru_hole circle
			(at 21.16748 1.35 90)
			(size 1.905 1.905)
			(drill 1.27)
			(layers "*.Cu" "*.Mask")
			(remove_unused_layers no)
			(net "GND")
			(thermal_bridge_angle 90)
		)
		(pad "P3" thru_hole circle
			(at 21.16748 -18.95 90)
			(size 1.905 1.905)
			(drill 1.27)
			(layers "*.Cu" "*.Mask")
			(remove_unused_layers no)
			(net "MAC_RF_OUT")
			(thermal_bridge_angle 90)
		)
		(pad "P4" thru_hole circle
			(at -19.43252 -18.95 90)
			(size 1.905 1.905)
			(drill 1.27)
			(layers "*.Cu" "*.Mask")
			(remove_unused_layers no)
			(net "GND")
			(thermal_bridge_angle 90)
		)
		(pad "P5" thru_hole circle
			(at -19.43252 21.65 90)
			(size 1.905 1.905)
			(drill 1.27)
			(layers "*.Cu" "*.Mask")
			(remove_unused_layers no)
			(net "MAC_VCC")
			(thermal_bridge_angle 90)
		)
		(pad "P6" thru_hole circle
			(at -17.33252 -21.65 90)
			(size 1.905 1.905)
			(drill 1.27)
			(layers "*.Cu" "*.Mask")
			(remove_unused_layers no)
			(net "MAC_BITE")
			(thermal_bridge_angle 90)
		)
		(pad "P7" thru_hole circle
			(at -14.33252 -21.65 90)
			(size 1.905 1.905)
			(drill 1.27)
			(layers "*.Cu" "*.Mask")
			(remove_unused_layers no)
			(net "MAC_RX")
			(thermal_bridge_angle 90)
		)
		(pad "P8" thru_hole circle
			(at -11.33252 -21.65 90)
			(size 1.905 1.905)
			(drill 1.27)
			(layers "*.Cu" "*.Mask")
			(remove_unused_layers no)
			(net "MAC_TX")
			(thermal_bridge_angle 90)
		)
		(pad "P9" thru_hole circle
			(at -8.28452 -21.65 90)
			(size 1.905 1.905)
			(drill 1.27)
			(layers "*.Cu" "*.Mask")
			(remove_unused_layers no)
			(net "MAC_PPS_IN")
			(thermal_bridge_angle 90)
		)
		(pad "P10" thru_hole circle
			(at -5.23652 -21.65 90)
			(size 1.905 1.905)
			(drill 1.27)
			(layers "*.Cu" "*.Mask")
			(remove_unused_layers no)
			(net "MAC_PPS_OUT")
			(thermal_bridge_angle 90)
		)
		(zone
			(layer "F.Cu")
			(hatch edge 0.5)
			(connect_pads
				(clearance 0)
			)
			(min_thickness 0.25)
			(keepout
				(tracks allowed)
				(vias allowed)
				(pads allowed)
				(copperpour not_allowed)
				(footprints allowed)
			)
			(placement
				(enabled no)
				(sheetname "")
			)
			(fill
				(thermal_gap 0.5)
				(thermal_bridge_width 0.5)
				(island_removal_mode 0)
			)
			(polygon
				(pts
					(xy 123.99358 134.0662) (xy 141.49359 134.0662) (xy 141.49359 140.0662) (xy 123.99358 140.0662)
				)
			)
		)
		(zone
			(layer "F.Cu")
			(hatch edge 0.5)
			(connect_pads
				(clearance 0)
			)
			(min_thickness 0.25)
			(keepout
				(tracks allowed)
				(vias allowed)
				(pads allowed)
				(copperpour not_allowed)
				(footprints allowed)
			)
			(placement
				(enabled no)
				(sheetname "")
			)
			(fill
				(thermal_gap 0.5)
				(thermal_bridge_width 0.5)
				(island_removal_mode 0)
			)
			(polygon
				(pts
					(xy 135.99358 120.0662) (xy 135.99359 110.0662) (xy 143.49359 110.0662) (xy 143.49358 120.0662)
				)
			)
		)
	)
	(footprint "Capacitors:CAPC2012X14N"
		(layer "F.Cu")
		(at 221.3637 90.9662)
		(property "Reference" "C8"
			(at 3 0.393345 0)
			(unlocked yes)
			(layer "F.SilkS")
			(effects
				(font
					(size 0.762 0.762)
					(thickness 0.2286)
				)
				(justify left bottom)
			)
		)
		(property "Value" "CAP_0805_10UF_25V"
			(at -2.6911 12.35119 0)
			(unlocked yes)
			(layer "F.SilkS")
			(hide yes)
			(effects
				(font
					(size 1.524 1.524)
					(thickness 0.254)
				)
				(justify left bottom)
			)
		)
		(sheetname "POWER")
		(sheetfile "POWER.kicad_sch")
		(duplicate_pad_numbers_are_jumpers no)
		(fp_line
			(start -0.762 -0.9652)
			(end 0.762 -0.9652)
			(stroke
				(width 0.1524)
				(type solid)
			)
			(layer "F.SilkS")
		)
		(fp_line
			(start -0.762 0.9652)
			(end 0.762 0.9652)
			(stroke
				(width 0.1524)
				(type solid)
			)
			(layer "F.SilkS")
		)
		(pad "1" smd rect
			(at -0.9 0 90)
			(size 1.45 1.15)
			(layers "F.Cu" "F.Mask" "F.Paste")
			(net "+3.3V")
		)
		(pad "2" smd rect
			(at 0.9 0 90)
			(size 1.45 1.15)
			(layers "F.Cu" "F.Mask" "F.Paste")
			(net "GND")
		)
	)
	(footprint "Passives:SOT65P210X110-3N"
		(layer "F.Cu")
		(at 224.9261 137.6162 -90)
		(property "Reference" "D8"
			(at -1.906655 -1.3 0)
			(unlocked yes)
			(layer "F.SilkS")
			(effects
				(font
					(size 0.762 0.762)
					(thickness 0.2286)
				)
				(justify left bottom)
			)
		)
		(property "Value" "BAT54SW"
			(at 7.49479 -2.7501 0)
			(unlocked yes)
			(layer "F.SilkS")
			(hide yes)
			(effects
				(font
					(size 1.524 1.524)
					(thickness 0.254)
				)
				(justify left bottom)
			)
		)
		(sheetname "PCIe_JTAG")
		(sheetfile "PCIe_JTAG.kicad_sch")
		(duplicate_pad_numbers_are_jumpers no)
		(fp_line
			(start 0.675 1.1)
			(end -0.325 1.1)
			(stroke
				(width 0.2)
				(type solid)
			)
			(layer "F.SilkS")
		)
		(fp_line
			(start 0.675 1.1)
			(end 0.675 0.65)
			(stroke
				(width 0.2)
				(type solid)
			)
			(layer "F.SilkS")
		)
		(fp_line
			(start 0.675 -0.65)
			(end 0.675 -1.1)
			(stroke
				(width 0.2)
				(type solid)
			)
			(layer "F.SilkS")
		)
		(fp_line
			(start 0.675 -1.1)
			(end -0.325 -1.1)
			(stroke
				(width 0.2)
				(type solid)
			)
			(layer "F.SilkS")
		)
		(fp_circle
			(center -1.125 -1.45)
			(end -1.25 -1.45)
			(stroke
				(width 0.25)
				(type solid)
			)
			(fill no)
			(layer "F.SilkS")
		)
		(pad "1" smd rect
			(at -1.125 -0.65)
			(size 0.5 0.9)
			(layers "F.Cu" "F.Mask" "F.Paste")
			(net "GND")
		)
		(pad "2" smd rect
			(at -1.125 0.65)
			(size 0.5 0.9)
			(layers "F.Cu" "F.Mask" "F.Paste")
			(net "+3.3V")
		)
		(pad "3" smd rect
			(at 1.125 0)
			(size 0.5 0.9)
			(layers "F.Cu" "F.Mask" "F.Paste")
			(net "FPGA_TDI")
		)
	)
	(footprint "Vault:RESC1608X55X30NL15T15"
		(layer "F.Cu")
		(at 82.1261 139.6162 -90)
		(property "Reference" "R32"
			(at 2.7714 -0.026921 90)
			(unlocked yes)
			(layer "F.SilkS")
			(effects
				(font
					(size 0.762 0.762)
					(thickness 0.2286)
				)
			)
		)
		(property "Value" "4.7K"
			(at -3.114792 2.39944 180)
			(unlocked yes)
			(layer "F.SilkS")
			(hide yes)
			(effects
				(font
					(size 1.524 1.524)
					(thickness 0.254)
				)
			)
		)
		(sheetname "USER_IO")
		(sheetfile "USER_IO.kicad_sch")
		(duplicate_pad_numbers_are_jumpers no)
		(pad "1" smd rect
			(at -0.75 0)
			(size 0.95 0.95)
			(layers "F.Cu" "F.Mask" "F.Paste")
			(net "ANT4_IO_IN")
		)
		(pad "2" smd rect
			(at 0.75 0)
			(size 0.95 0.95)
			(layers "F.Cu" "F.Mask" "F.Paste")
			(net "+3.3V")
		)
	)
	(footprint "Vault:SOT143-4L"
		(layer "F.Cu")
		(at 71.8761 128.1162 90)
		(property "Reference" "D2"
			(at -2.926921 1.178595 0)
			(unlocked yes)
			(layer "F.SilkS")
			(effects
				(font
					(size 0.762 0.762)
					(thickness 0.2286)
				)
			)
		)
		(property "Value" "8240136"
			(at 2.7035 3.368802 90)
			(unlocked yes)
			(layer "F.SilkS")
			(hide yes)
			(effects
				(font
					(size 1.524 1.524)
					(thickness 0.254)
				)
			)
		)
		(sheetname "USER_IO")
		(sheetfile "USER_IO.kicad_sch")
		(duplicate_pad_numbers_are_jumpers no)
		(fp_line
			(start 2.05 -1.7)
			(end 2.05 1.7)
			(stroke
				(width 0.2)
				(type solid)
			)
			(layer "F.SilkS")
		)
		(fp_line
			(start -2.05 -1.7)
			(end 2.05 -1.7)
			(stroke
				(width 0.2)
				(type solid)
			)
			(layer "F.SilkS")
		)
		(fp_line
			(start -2.05 -1.7)
			(end -2.05 1.675)
			(stroke
				(width 0.2)
				(type solid)
			)
			(layer "F.SilkS")
		)
		(fp_line
			(start -2.05 1.7)
			(end 2.05 1.7)
			(stroke
				(width 0.2)
				(type solid)
			)
			(layer "F.SilkS")
		)
		(fp_circle
			(center -2.404 -1.075)
			(end -2.15 -1.075)
			(stroke
				(width 0.2)
				(type solid)
			)
			(fill no)
			(layer "F.SilkS")
		)
		(pad "1" smd rect
			(at -1.1 -0.75 180)
			(size 1.4 1.4)
			(layers "F.Cu" "F.Mask" "F.Paste")
			(net "GND")
		)
		(pad "2" smd rect
			(at -1.1 0.95 180)
			(size 1 1.4)
			(layers "F.Cu" "F.Mask" "F.Paste")
			(net "NetAN4_1")
		)
		(pad "3" smd rect
			(at 1.1 0.95 180)
			(size 1 1.4)
			(layers "F.Cu" "F.Mask" "F.Paste")
			(net "NetAN3_1")
		)
		(pad "4" smd rect
			(at 1.1 -0.95 180)
			(size 1 1.4)
			(layers "F.Cu" "F.Mask" "F.Paste")
			(net "+3.3V")
		)
	)
	(footprint "Vault:CAPC1608X87X45ML20T05"
		(layer "F.Cu")
		(at 214.7435 116.3062 90)
		(property "Reference" "C16"
			(at 1.74 0.638345 90)
			(unlocked yes)
			(layer "F.SilkS")
			(effects
				(font
					(size 0.762 0.762)
					(thickness 0.2286)
				)
				(justify left bottom)
			)
		)
		(property "Value" "0.1uF"
			(at -6.58639 -2.4645 0)
			(unlocked yes)
			(layer "F.SilkS")
			(hide yes)
			(effects
				(font
					(size 1.524 1.524)
					(thickness 0.254)
				)
				(justify left bottom)
			)
		)
		(sheetname "POWER")
		(sheetfile "POWER.kicad_sch")
		(duplicate_pad_numbers_are_jumpers no)
		(pad "1" smd rect
			(at -0.7 0 180)
			(size 1.1 1.05)
			(layers "F.Cu" "F.Mask" "F.Paste")
			(net "GND")
		)
		(pad "2" smd rect
			(at 0.7 0 180)
			(size 1.1 1.05)
			(layers "F.Cu" "F.Mask" "F.Paste")
			(net "+5.0V")
		)
	)
	(footprint "Vault:FP-BME280-MFG"
		(layer "F.Cu")
		(at 194.1261 86.8286)
		(property "Reference" "U14"
			(at -0.5214 2.776921 0)
			(unlocked yes)
			(layer "F.SilkS")
			(effects
				(font
					(size 0.762 0.762)
					(thickness 0.2286)
				)
			)
		)
		(property "Value" "BME280"
			(at 2.932305 3.470402 0)
			(unlocked yes)
			(layer "F.SilkS")
			(hide yes)
			(effects
				(font
					(size 1.524 1.524)
					(thickness 0.254)
				)
			)
		)
		(sheetname "GPS_IMU_SENSORS")
		(sheetfile "GPS_IMU_SENSORS.kicad_sch")
		(duplicate_pad_numbers_are_jumpers no)
		(fp_line
			(start -1.3 -1.55)
			(end 1.3 -1.55)
			(stroke
				(width 0.2)
				(type solid)
			)
			(layer "F.SilkS")
		)
		(fp_line
			(start -1.3 1.55)
			(end 1.3 1.55)
			(stroke
				(width 0.2)
				(type solid)
			)
			(layer "F.SilkS")
		)
		(fp_circle
			(center 1.85 -0.975)
			(end 1.85 -1.1)
			(stroke
				(width 0.25)
				(type solid)
			)
			(fill no)
			(layer "F.SilkS")
		)
		(fp_line
			(start -1.8 -1.8)
			(end 1.8 -1.8)
			(stroke
				(width 0.2)
				(type solid)
			)
			(layer "F.CrtYd")
		)
		(fp_line
			(start -1.8 1.8)
			(end -1.8 -1.8)
			(stroke
				(width 0.2)
				(type solid)
			)
			(layer "F.CrtYd")
		)
		(fp_line
			(start -1.8 1.8)
			(end 1.8 1.8)
			(stroke
				(width 0.2)
				(type solid)
			)
			(layer "F.CrtYd")
		)
		(fp_line
			(start 1.8 1.8)
			(end 1.8 -1.8)
			(stroke
				(width 0.2)
				(type solid)
			)
			(layer "F.CrtYd")
		)
		(fp_line
			(start -1.8 -1.8)
			(end 1.8 -1.8)
			(stroke
				(width 0.2)
				(type solid)
			)
			(layer "F.Fab")
		)
		(fp_line
			(start -1.8 1.8)
			(end -1.8 -1.8)
			(stroke
				(width 0.2)
				(type solid)
			)
			(layer "F.Fab")
		)
		(fp_line
			(start -1.8 1.8)
			(end 1.8 1.8)
			(stroke
				(width 0.2)
				(type solid)
			)
			(layer "F.Fab")
		)
		(fp_line
			(start -0.5 0)
			(end 0.5 0)
			(stroke
				(width 0.1)
				(type solid)
			)
			(layer "F.Fab")
		)
		(fp_line
			(start 0 0.5)
			(end 0 -0.5)
			(stroke
				(width 0.1)
				(type solid)
			)
			(layer "F.Fab")
		)
		(fp_line
			(start 1.8 1.8)
			(end 1.8 -1.8)
			(stroke
				(width 0.2)
				(type solid)
			)
			(layer "F.Fab")
		)
		(fp_text user "${REFERENCE}"
			(at 0 0.28425 0)
			(unlocked yes)
			(layer "F.Fab")
			(effects
				(font
					(face "Arial")
					(size 0.63 0.63)
					(thickness 0.1)
				)
				(justify left bottom)
			)
		)
		(pad "1" smd rect
			(at 1.025 -0.975)
			(size 0.5 0.35)
			(layers "F.Cu" "F.Mask" "F.Paste")
			(net "GND")
			(solder_mask_margin 0)
			(solder_paste_margin 0)
		)
		(pad "2" smd rect
			(at 1.025 -0.325)
			(size 0.5 0.35)
			(layers "F.Cu" "F.Mask" "F.Paste")
			(net "+3.3V")
			(solder_mask_margin 0)
			(solder_paste_margin 0)
		)
		(pad "3" smd rect
			(at 1.025 0.325)
			(size 0.5 0.35)
			(layers "F.Cu" "F.Mask" "F.Paste")
			(net "SDA")
			(solder_mask_margin 0)
			(solder_paste_margin 0)
		)
		(pad "4" smd rect
			(at 1.025 0.975)
			(size 0.5 0.35)
			(layers "F.Cu" "F.Mask" "F.Paste")
			(net "SCL")
			(solder_mask_margin 0)
			(solder_paste_margin 0)
		)
		(pad "5" smd rect
			(at -1.025 0.975)
			(size 0.5 0.35)
			(layers "F.Cu" "F.Mask" "F.Paste")
			(net "GND")
			(solder_mask_margin 0)
			(solder_paste_margin 0)
		)
		(pad "6" smd rect
			(at -1.025 0.325)
			(size 0.5 0.35)
			(layers "F.Cu" "F.Mask" "F.Paste")
			(net "+3.3V")
			(solder_mask_margin 0)
			(solder_paste_margin 0)
		)
		(pad "7" smd rect
			(at -1.025 -0.325)
			(size 0.5 0.35)
			(layers "F.Cu" "F.Mask" "F.Paste")
			(net "GND")
			(solder_mask_margin 0)
			(solder_paste_margin 0)
		)
		(pad "8" smd rect
			(at -1.025 -0.975)
			(size 0.5 0.35)
			(layers "F.Cu" "F.Mask" "F.Paste")
			(net "+3.3V")
			(solder_mask_margin 0)
			(solder_paste_margin 0)
		)
	)
)
